(kicad_pcb
	(version 20260206)
	(generator "pcbnew")
	(generator_version "10.0")
	(general
		(thickness 1.6)
		(legacy_teardrops no)
	)
	(paper "A4")
	(title_block
		(title "Bryce Canyon_IOM_IOC_16318-2_OCP.brd")
		(comment 1 "Bryce Canyon / footprints 1504-1511 of 1605")
	)
	(layers
		(0 "F.Cu" signal "TOP")
		(4 "In1.Cu" signal "L2GND")
		(6 "In2.Cu" signal "L3")
		(8 "In3.Cu" signal "L4VCC")
		(10 "In4.Cu" signal "L5VCC")
		(12 "In5.Cu" signal "L6")
		(14 "In6.Cu" signal "L7GND")
		(2 "B.Cu" signal "BOTTOM")
		(9 "F.Adhes" user "F.Adhesive")
		(11 "B.Adhes" user "B.Adhesive")
		(13 "F.Paste" user "Package Geometry/Pastemask Top")
		(15 "B.Paste" user "Package Geometry/Pastemask Bottom")
		(5 "F.SilkS" user "Ref Des/Silkscreen Top")
		(7 "B.SilkS" user "Ref Des/Silkscreen Bottom")
		(1 "F.Mask" user "Board Geometry/Soldermask Top")
		(3 "B.Mask" user "Board Geometry/Soldermask Bottom")
		(17 "Dwgs.User" user "User.Drawings")
		(19 "Cmts.User" user "User.Comments")
		(21 "Eco1.User" user "User.Eco1")
		(23 "Eco2.User" user "User.Eco2")
		(25 "Edge.Cuts" user "Board Geometry/Outline")
		(27 "Margin" user)
		(31 "F.CrtYd" user "Package Geometry/Place Bound Top")
		(29 "B.CrtYd" user "Package Geometry/Place Bound Bottom")
		(35 "F.Fab" user "Ref Des/Assembly Top")
		(33 "B.Fab" user "Ref Des/Assembly Bottom")
	)
	(footprint ""
		(layer "B.Cu")
		(at 168.656 -106.045 -90)
		(property "Reference" "C448"
			(at 0 0 90)
			(layer "B.SilkS")
			(hide yes)
			(effects
				(font
					(size 1.27 1.27)
				)
				(justify mirror)
			)
		)
		(property "Value" "SCD1U16V2KX-3GP"
			(at -1.1811 -2.7051 270)
			(unlocked yes)
			(layer "B.Fab")
			(hide yes)
			(effects
				(font
					(size 1.016 1.016)
					(thickness 0.1524)
				)
				(justify mirror)
			)
		)
		(property "Device Type" "C402H22"
			(at -1.1811 -4.2291 270)
			(unlocked yes)
			(layer "B.Fab")
			(hide yes)
			(effects
				(font
					(size 1.016 1.016)
					(thickness 0.1524)
				)
				(justify mirror)
			)
		)
		(duplicate_pad_numbers_are_jumpers no)
		(fp_rect
			(start 0.4318 0.9525)
			(end -0.4318 -0.9525)
			(stroke
				(width 0)
				(type default)
			)
			(fill no)
			(layer "B.CrtYd")
		)
		(fp_rect
			(start 0.4318 0.9525)
			(end -0.4318 -0.9525)
			(stroke
				(width 0)
				(type default)
			)
			(fill no)
			(layer "B.Fab")
		)
		(pad "1" smd custom
			(at 0 -0.4445 90)
			(size 0.1524 0.1524)
			(layers "B.Cu" "B.Mask" "B.Paste")
			(net "P1V8")
			(options
				(clearance outline)
				(anchor circle)
			)
			(primitives
				(gr_poly
					(pts
						(arc
							(start 0.3048 0.2032)
							(mid 0.275042 0.275042)
							(end 0.2032 0.3048)
						)
						(arc
							(start -0.2032 0.3048)
							(mid -0.275042 0.275042)
							(end -0.3048 0.2032)
						)
						(arc
							(start -0.3048 -0.2032)
							(mid -0.275042 -0.275042)
							(end -0.2032 -0.3048)
						)
						(arc
							(start 0.2032 -0.3048)
							(mid 0.275042 -0.275042)
							(end 0.3048 -0.2032)
						)
					)
					(width 0)
					(fill yes)
				)
			)
		)
		(pad "2" smd custom
			(at 0 0.4445 90)
			(size 0.1524 0.1524)
			(layers "B.Cu" "B.Mask" "B.Paste")
			(net "GND")
			(options
				(clearance outline)
				(anchor circle)
			)
			(primitives
				(gr_poly
					(pts
						(arc
							(start 0.3048 0.2032)
							(mid 0.275042 0.275042)
							(end 0.2032 0.3048)
						)
						(arc
							(start -0.2032 0.3048)
							(mid -0.275042 0.275042)
							(end -0.3048 0.2032)
						)
						(arc
							(start -0.3048 -0.2032)
							(mid -0.275042 -0.275042)
							(end -0.2032 -0.3048)
						)
						(arc
							(start 0.2032 -0.3048)
							(mid 0.275042 -0.275042)
							(end 0.3048 -0.2032)
						)
					)
					(width 0)
					(fill yes)
				)
			)
		)
	)
	(footprint ""
		(layer "B.Cu")
		(at 205.994 -59.5122)
		(property "Reference" "TP122"
			(at 0 0 0)
			(layer "B.SilkS")
			(hide yes)
			(effects
				(font
					(size 1.27 1.27)
				)
				(justify mirror)
			)
		)
		(property "Value" "TPAD28-2-GP"
			(at 0.0127 -1.6637 0)
			(unlocked yes)
			(layer "B.Fab")
			(hide yes)
			(effects
				(font
					(size 1.016 1.016)
					(thickness 0.1524)
				)
				(justify mirror)
			)
		)
		(property "Device Type" "TPAD28"
			(at 0.0127 -3.1877 0)
			(unlocked yes)
			(layer "B.Fab")
			(hide yes)
			(effects
				(font
					(size 1.016 1.016)
					(thickness 0.1524)
				)
				(justify mirror)
			)
		)
		(duplicate_pad_numbers_are_jumpers no)
		(fp_poly
			(pts
				(arc
					(start 0.3556 0)
					(mid -0.3556 0)
					(end 0.3556 0)
				)
			)
			(stroke
				(width 0)
				(type default)
			)
			(fill no)
			(layer "B.CrtYd")
		)
		(fp_poly
			(pts
				(arc
					(start 0.6096 0)
					(mid -0.6096 0)
					(end 0.6096 0)
				)
			)
			(stroke
				(width 0)
				(type default)
			)
			(fill no)
			(layer "B.Fab")
		)
		(pad "1" smd circle
			(at 0 0 180)
			(size 0.7112 0.7112)
			(layers "B.Cu" "B.Mask" "B.Paste")
			(net "SIO_DIN_1")
		)
	)
	(footprint ""
		(layer "B.Cu")
		(at 196.6849 -65.1129 180)
		(property "Reference" "C397"
			(at 0 0 0)
			(layer "B.SilkS")
			(hide yes)
			(effects
				(font
					(size 1.27 1.27)
				)
				(justify mirror)
			)
		)
		(property "Value" "SCD1U6D3V1KX-GP"
			(at 2.8321 -1.7399 180)
			(unlocked yes)
			(layer "B.Fab")
			(hide yes)
			(effects
				(font
					(size 1.016 1.016)
					(thickness 0.1524)
				)
				(justify mirror)
			)
		)
		(property "Device Type" "C0201H13"
			(at 2.8321 -3.2639 180)
			(unlocked yes)
			(layer "B.Fab")
			(hide yes)
			(effects
				(font
					(size 1.016 1.016)
					(thickness 0.1524)
				)
				(justify mirror)
			)
		)
		(duplicate_pad_numbers_are_jumpers no)
		(fp_rect
			(start 0.2794 0.6477)
			(end -0.2794 -0.6477)
			(stroke
				(width 0)
				(type default)
			)
			(fill no)
			(layer "B.CrtYd")
		)
		(fp_rect
			(start 0.2794 0.6477)
			(end -0.2794 -0.6477)
			(stroke
				(width 0)
				(type default)
			)
			(fill no)
			(layer "B.Fab")
		)
		(pad "1" smd custom
			(at 0 -0.2794)
			(size 0.0762 0.0762)
			(layers "B.Cu" "B.Mask" "B.Paste")
			(net "P0V975")
			(options
				(clearance outline)
				(anchor circle)
			)
			(primitives
				(gr_poly
					(pts
						(arc
							(start 0.1524 0.127)
							(mid 0.137521 0.162921)
							(end 0.1016 0.1778)
						)
						(arc
							(start -0.1016 0.1778)
							(mid -0.137521 0.162921)
							(end -0.1524 0.127)
						)
						(arc
							(start -0.1524 -0.127)
							(mid -0.137521 -0.162921)
							(end -0.1016 -0.1778)
						)
						(arc
							(start 0.1016 -0.1778)
							(mid 0.137521 -0.162921)
							(end 0.1524 -0.127)
						)
					)
					(width 0)
					(fill yes)
				)
			)
		)
		(pad "2" smd custom
			(at 0 0.2794)
			(size 0.0762 0.0762)
			(layers "B.Cu" "B.Mask" "B.Paste")
			(net "GND")
			(options
				(clearance outline)
				(anchor circle)
			)
			(primitives
				(gr_poly
					(pts
						(arc
							(start 0.1524 0.127)
							(mid 0.137521 0.162921)
							(end 0.1016 0.1778)
						)
						(arc
							(start -0.1016 0.1778)
							(mid -0.137521 0.162921)
							(end -0.1524 0.127)
						)
						(arc
							(start -0.1524 -0.127)
							(mid -0.137521 -0.162921)
							(end -0.1016 -0.1778)
						)
						(arc
							(start 0.1016 -0.1778)
							(mid 0.137521 -0.162921)
							(end 0.1524 -0.127)
						)
					)
					(width 0)
					(fill yes)
				)
			)
		)
	)
	(footprint ""
		(layer "B.Cu")
		(at 79.8576 -145.542 -90)
		(property "Reference" "R128"
			(at 0 0 90)
			(layer "B.SilkS")
			(hide yes)
			(effects
				(font
					(size 1.27 1.27)
				)
				(justify mirror)
			)
		)
		(property "Value" "0R2J-2-GP"
			(at -0.064008 -3.993896 270)
			(unlocked yes)
			(layer "B.Fab")
			(hide yes)
			(effects
				(font
					(size 1.016 1.016)
					(thickness 0.1524)
				)
				(justify mirror)
			)
		)
		(property "Device Type" "R402H16"
			(at -0.064008 -5.517896 270)
			(unlocked yes)
			(layer "B.Fab")
			(hide yes)
			(effects
				(font
					(size 1.016 1.016)
					(thickness 0.1524)
				)
				(justify mirror)
			)
		)
		(duplicate_pad_numbers_are_jumpers no)
		(fp_line
			(start -0.508 -0.9398)
			(end 0.508 -0.9398)
			(stroke
				(width 0.1524)
				(type default)
			)
			(layer "B.SilkS")
		)
		(fp_line
			(start 0.508 -0.9398)
			(end 0.508 0.9398)
			(stroke
				(width 0.1524)
				(type default)
			)
			(layer "B.SilkS")
		)
		(fp_rect
			(start 0.508 0.9398)
			(end -0.508 -0.9398)
			(stroke
				(width 0)
				(type default)
			)
			(fill no)
			(layer "B.CrtYd")
		)
		(fp_rect
			(start 0.508 0.9398)
			(end -0.508 -0.9398)
			(stroke
				(width 0)
				(type default)
			)
			(fill no)
			(layer "B.Fab")
		)
		(pad "1" smd custom
			(at 0 -0.4445 90)
			(size 0.1397 0.1397)
			(layers "B.Cu" "B.Mask" "B.Paste")
			(net "I2C_EXP_LOC_SDA")
			(options
				(clearance outline)
				(anchor circle)
			)
			(primitives
				(gr_poly
					(pts
						(arc
							(start -0.1778 0.2794)
							(mid -0.249642 0.249642)
							(end -0.2794 0.1778)
						)
						(arc
							(start -0.2794 -0.1778)
							(mid -0.249642 -0.249642)
							(end -0.1778 -0.2794)
						)
						(arc
							(start 0.1778 -0.2794)
							(mid 0.249642 -0.249642)
							(end 0.2794 -0.1778)
						)
						(arc
							(start 0.2794 0.1778)
							(mid 0.249642 0.249642)
							(end 0.1778 0.2794)
						)
					)
					(width 0)
					(fill yes)
				)
			)
		)
		(pad "2" smd custom
			(at 0 0.4445 90)
			(size 0.1397 0.1397)
			(layers "B.Cu" "B.Mask" "B.Paste")
			(net "I2C_EXP_LOC_SDA_R")
			(options
				(clearance outline)
				(anchor circle)
			)
			(primitives
				(gr_poly
					(pts
						(arc
							(start -0.1778 0.2794)
							(mid -0.249642 0.249642)
							(end -0.2794 0.1778)
						)
						(arc
							(start -0.2794 -0.1778)
							(mid -0.249642 -0.249642)
							(end -0.1778 -0.2794)
						)
						(arc
							(start 0.1778 -0.2794)
							(mid 0.249642 -0.249642)
							(end 0.2794 -0.1778)
						)
						(arc
							(start 0.2794 0.1778)
							(mid 0.249642 0.249642)
							(end 0.1778 0.2794)
						)
					)
					(width 0)
					(fill yes)
				)
			)
		)
	)
	(footprint ""
		(layer "B.Cu")
		(at 78.9051 -167.1447 -90)
		(property "Reference" "R651"
			(at 0 0 90)
			(layer "B.SilkS")
			(hide yes)
			(effects
				(font
					(size 1.27 1.27)
				)
				(justify mirror)
			)
		)
		(property "Value" "0R2J-2-GP"
			(at -0.064008 -3.993896 270)
			(unlocked yes)
			(layer "B.Fab")
			(hide yes)
			(effects
				(font
					(size 1.016 1.016)
					(thickness 0.1524)
				)
				(justify mirror)
			)
		)
		(property "Device Type" "R402H16"
			(at -0.064008 -5.517896 270)
			(unlocked yes)
			(layer "B.Fab")
			(hide yes)
			(effects
				(font
					(size 1.016 1.016)
					(thickness 0.1524)
				)
				(justify mirror)
			)
		)
		(duplicate_pad_numbers_are_jumpers no)
		(fp_line
			(start -0.508 -0.9398)
			(end 0.508 -0.9398)
			(stroke
				(width 0.1524)
				(type default)
			)
			(layer "B.SilkS")
		)
		(fp_line
			(start 0.508 -0.9398)
			(end 0.508 0.9398)
			(stroke
				(width 0.1524)
				(type default)
			)
			(layer "B.SilkS")
		)
		(fp_rect
			(start 0.508 0.9398)
			(end -0.508 -0.9398)
			(stroke
				(width 0)
				(type default)
			)
			(fill no)
			(layer "B.CrtYd")
		)
		(fp_rect
			(start 0.508 0.9398)
			(end -0.508 -0.9398)
			(stroke
				(width 0)
				(type default)
			)
			(fill no)
			(layer "B.Fab")
		)
		(pad "1" smd custom
			(at 0 -0.4445 90)
			(size 0.1397 0.1397)
			(layers "B.Cu" "B.Mask" "B.Paste")
			(net "EXP_UART_EN_R")
			(options
				(clearance outline)
				(anchor circle)
			)
			(primitives
				(gr_poly
					(pts
						(arc
							(start -0.1778 0.2794)
							(mid -0.249642 0.249642)
							(end -0.2794 0.1778)
						)
						(arc
							(start -0.2794 -0.1778)
							(mid -0.249642 -0.249642)
							(end -0.1778 -0.2794)
						)
						(arc
							(start 0.1778 -0.2794)
							(mid 0.249642 -0.249642)
							(end 0.2794 -0.1778)
						)
						(arc
							(start 0.2794 0.1778)
							(mid 0.249642 0.249642)
							(end 0.1778 0.2794)
						)
					)
					(width 0)
					(fill yes)
				)
			)
		)
		(pad "2" smd custom
			(at 0 0.4445 90)
			(size 0.1397 0.1397)
			(layers "B.Cu" "B.Mask" "B.Paste")
			(net "EXP_UART_EN")
			(options
				(clearance outline)
				(anchor circle)
			)
			(primitives
				(gr_poly
					(pts
						(arc
							(start -0.1778 0.2794)
							(mid -0.249642 0.249642)
							(end -0.2794 0.1778)
						)
						(arc
							(start -0.2794 -0.1778)
							(mid -0.249642 -0.249642)
							(end -0.1778 -0.2794)
						)
						(arc
							(start 0.1778 -0.2794)
							(mid 0.249642 -0.249642)
							(end 0.2794 -0.1778)
						)
						(arc
							(start 0.2794 0.1778)
							(mid 0.249642 0.249642)
							(end 0.1778 0.2794)
						)
					)
					(width 0)
					(fill yes)
				)
			)
		)
	)
	(footprint ""
		(layer "B.Cu")
		(at 195.5292 -65.3669 90)
		(property "Reference" "C405"
			(at 0 0 90)
			(layer "B.SilkS")
			(hide yes)
			(effects
				(font
					(size 1.27 1.27)
				)
				(justify mirror)
			)
		)
		(property "Value" "SCD1U6D3V1KX-GP"
			(at 2.8321 -1.7399 90)
			(unlocked yes)
			(layer "B.Fab")
			(hide yes)
			(effects
				(font
					(size 1.016 1.016)
					(thickness 0.1524)
				)
				(justify mirror)
			)
		)
		(property "Device Type" "C0201H13"
			(at 2.8321 -3.2639 90)
			(unlocked yes)
			(layer "B.Fab")
			(hide yes)
			(effects
				(font
					(size 1.016 1.016)
					(thickness 0.1524)
				)
				(justify mirror)
			)
		)
		(duplicate_pad_numbers_are_jumpers no)
		(fp_rect
			(start 0.2794 0.6477)
			(end -0.2794 -0.6477)
			(stroke
				(width 0)
				(type default)
			)
			(fill no)
			(layer "B.CrtYd")
		)
		(fp_rect
			(start 0.2794 0.6477)
			(end -0.2794 -0.6477)
			(stroke
				(width 0)
				(type default)
			)
			(fill no)
			(layer "B.Fab")
		)
		(pad "1" smd custom
			(at 0 -0.2794 270)
			(size 0.0762 0.0762)
			(layers "B.Cu" "B.Mask" "B.Paste")
			(net "P0V975")
			(options
				(clearance outline)
				(anchor circle)
			)
			(primitives
				(gr_poly
					(pts
						(arc
							(start 0.1524 0.127)
							(mid 0.137521 0.162921)
							(end 0.1016 0.1778)
						)
						(arc
							(start -0.1016 0.1778)
							(mid -0.137521 0.162921)
							(end -0.1524 0.127)
						)
						(arc
							(start -0.1524 -0.127)
							(mid -0.137521 -0.162921)
							(end -0.1016 -0.1778)
						)
						(arc
							(start 0.1016 -0.1778)
							(mid 0.137521 -0.162921)
							(end 0.1524 -0.127)
						)
					)
					(width 0)
					(fill yes)
				)
			)
		)
		(pad "2" smd custom
			(at 0 0.2794 270)
			(size 0.0762 0.0762)
			(layers "B.Cu" "B.Mask" "B.Paste")
			(net "GND")
			(options
				(clearance outline)
				(anchor circle)
			)
			(primitives
				(gr_poly
					(pts
						(arc
							(start 0.1524 0.127)
							(mid 0.137521 0.162921)
							(end 0.1016 0.1778)
						)
						(arc
							(start -0.1016 0.1778)
							(mid -0.137521 0.162921)
							(end -0.1524 0.127)
						)
						(arc
							(start -0.1524 -0.127)
							(mid -0.137521 -0.162921)
							(end -0.1016 -0.1778)
						)
						(arc
							(start 0.1016 -0.1778)
							(mid 0.137521 -0.162921)
							(end 0.1524 -0.127)
						)
					)
					(width 0)
					(fill yes)
				)
			)
		)
	)
	(footprint ""
		(layer "B.Cu")
		(at 42.382694 -125.12548)
		(property "Reference" "R364"
			(at 0 0 0)
			(layer "B.SilkS")
			(hide yes)
			(effects
				(font
					(size 1.27 1.27)
				)
				(justify mirror)
			)
		)
		(property "Value" "4K7R2F-GP"
			(at -0.064008 -3.993896 0)
			(unlocked yes)
			(layer "B.Fab")
			(hide yes)
			(effects
				(font
					(size 1.016 1.016)
					(thickness 0.1524)
				)
				(justify mirror)
			)
		)
		(property "Device Type" "R402H16"
			(at -0.064008 -5.517896 0)
			(unlocked yes)
			(layer "B.Fab")
			(hide yes)
			(effects
				(font
					(size 1.016 1.016)
					(thickness 0.1524)
				)
				(justify mirror)
			)
		)
		(duplicate_pad_numbers_are_jumpers no)
		(fp_line
			(start -0.508 -0.9398)
			(end 0.508 -0.9398)
			(stroke
				(width 0.1524)
				(type default)
			)
			(layer "B.SilkS")
		)
		(fp_line
			(start 0.508 -0.9398)
			(end 0.508 0.9398)
			(stroke
				(width 0.1524)
				(type default)
			)
			(layer "B.SilkS")
		)
		(fp_rect
			(start 0.508 0.9398)
			(end -0.508 -0.9398)
			(stroke
				(width 0)
				(type default)
			)
			(fill no)
			(layer "B.CrtYd")
		)
		(fp_rect
			(start 0.508 0.9398)
			(end -0.508 -0.9398)
			(stroke
				(width 0)
				(type default)
			)
			(fill no)
			(layer "B.Fab")
		)
		(pad "1" smd custom
			(at 0 -0.4445 180)
			(size 0.1397 0.1397)
			(layers "B.Cu" "B.Mask" "B.Paste")
			(net "FM_BMC_RESET_N")
			(options
				(clearance outline)
				(anchor circle)
			)
			(primitives
				(gr_poly
					(pts
						(arc
							(start -0.1778 0.2794)
							(mid -0.249642 0.249642)
							(end -0.2794 0.1778)
						)
						(arc
							(start -0.2794 -0.1778)
							(mid -0.249642 -0.249642)
							(end -0.1778 -0.2794)
						)
						(arc
							(start 0.1778 -0.2794)
							(mid 0.249642 -0.249642)
							(end 0.2794 -0.1778)
						)
						(arc
							(start 0.2794 0.1778)
							(mid 0.249642 0.249642)
							(end 0.1778 0.2794)
						)
					)
					(width 0)
					(fill yes)
				)
			)
		)
		(pad "2" smd custom
			(at 0 0.4445 180)
			(size 0.1397 0.1397)
			(layers "B.Cu" "B.Mask" "B.Paste")
			(net "GND")
			(options
				(clearance outline)
				(anchor circle)
			)
			(primitives
				(gr_poly
					(pts
						(arc
							(start -0.1778 0.2794)
							(mid -0.249642 0.249642)
							(end -0.2794 0.1778)
						)
						(arc
							(start -0.2794 -0.1778)
							(mid -0.249642 -0.249642)
							(end -0.1778 -0.2794)
						)
						(arc
							(start 0.1778 -0.2794)
							(mid 0.249642 -0.249642)
							(end 0.2794 -0.1778)
						)
						(arc
							(start 0.2794 0.1778)
							(mid 0.249642 0.249642)
							(end 0.1778 0.2794)
						)
					)
					(width 0)
					(fill yes)
				)
			)
		)
	)
	(footprint ""
		(layer "B.Cu")
		(at 174.5742 -68.3768 90)
		(property "Reference" "R583"
			(at 0 0 90)
			(layer "B.SilkS")
			(hide yes)
			(effects
				(font
					(size 1.27 1.27)
				)
				(justify mirror)
			)
		)
		(property "Value" "2K2R2F-GP"
			(at -0.064008 -3.993896 90)
			(unlocked yes)
			(layer "B.Fab")
			(hide yes)
			(effects
				(font
					(size 1.016 1.016)
					(thickness 0.1524)
				)
				(justify mirror)
			)
		)
		(property "Device Type" "R402H16"
			(at -0.064008 -5.517896 90)
			(unlocked yes)
			(layer "B.Fab")
			(hide yes)
			(effects
				(font
					(size 1.016 1.016)
					(thickness 0.1524)
				)
				(justify mirror)
			)
		)
		(duplicate_pad_numbers_are_jumpers no)
		(fp_line
			(start 0.508 -0.9398)
			(end 0.508 0.9398)
			(stroke
				(width 0.1524)
				(type default)
			)
			(layer "B.SilkS")
		)
		(fp_line
			(start -0.508 -0.9398)
			(end 0.508 -0.9398)
			(stroke
				(width 0.1524)
				(type default)
			)
			(layer "B.SilkS")
		)
		(fp_rect
			(start 0.508 0.9398)
			(end -0.508 -0.9398)
			(stroke
				(width 0)
				(type default)
			)
			(fill no)
			(layer "B.CrtYd")
		)
		(fp_rect
			(start 0.508 0.9398)
			(end -0.508 -0.9398)
			(stroke
				(width 0)
				(type default)
			)
			(fill no)
			(layer "B.Fab")
		)
		(pad "1" smd custom
			(at 0 -0.4445 270)
			(size 0.1397 0.1397)
			(layers "B.Cu" "B.Mask" "B.Paste")
			(net "P1V8")
			(options
				(clearance outline)
				(anchor circle)
			)
			(primitives
				(gr_poly
					(pts
						(arc
							(start -0.1778 0.2794)
							(mid -0.249642 0.249642)
							(end -0.2794 0.1778)
						)
						(arc
							(start -0.2794 -0.1778)
							(mid -0.249642 -0.249642)
							(end -0.1778 -0.2794)
						)
						(arc
							(start 0.1778 -0.2794)
							(mid 0.249642 -0.249642)
							(end 0.2794 -0.1778)
						)
						(arc
							(start 0.2794 0.1778)
							(mid 0.249642 0.249642)
							(end 0.1778 0.2794)
						)
					)
					(width 0)
					(fill yes)
				)
			)
		)
		(pad "2" smd custom
			(at 0 0.4445 270)
			(size 0.1397 0.1397)
			(layers "B.Cu" "B.Mask" "B.Paste")
			(net "IOC_SCL_2")
			(options
				(clearance outline)
				(anchor circle)
			)
			(primitives
				(gr_poly
					(pts
						(arc
							(start -0.1778 0.2794)
							(mid -0.249642 0.249642)
							(end -0.2794 0.1778)
						)
						(arc
							(start -0.2794 -0.1778)
							(mid -0.249642 -0.249642)
							(end -0.1778 -0.2794)
						)
						(arc
							(start 0.1778 -0.2794)
							(mid 0.249642 -0.249642)
							(end 0.2794 -0.1778)
						)
						(arc
							(start 0.2794 0.1778)
							(mid 0.249642 0.249642)
							(end 0.1778 0.2794)
						)
					)
					(width 0)
					(fill yes)
				)
			)
		)
	)
)
